FILE_TYPE = MULTI_PHYS_TABLE;

PART '74LVC1G07GW'

{========================================================================================}
:VALUE         | PART_TYPE | MATERIAL | PART_NUMBER      = PART_NUMBER   | JEDEC_TYPE | DESCRIPTION                  | MANUFTR | MANUF_PN      | RD_CMPLS_LVL | CMPLS_LVL | FROM_PJ      | CLASS | DIP_SMD | DATA                | EE_CHECK_LIST | FP_ECN | PSL | LIFECYCLE      | CREATOR | STANDARD | CREATEDAY  | STATUS   ;
{========================================================================================}
 '74LVC1G07GW' | 'SMLF'    | 'IC'     | 'ALVC1G07002'(!) = 'ALVC1G07002' |'SOT353_Q'| 'IC(5P) 74LVC1G07GW(SOT353)' | 'PHI'   | '74LVC1G07GW' | ''           | 'EP'      | 'JS1-STEVEN' | 'IC'  | ''      | 'PHI_74LVC1G07.pdf' | ''            | ''     | ''  | ''               | ''      | ''               | '20111207' | 'Normal'
 '74LVC1G07GW' | 'SMLF'    | 'EMPTY'  | 'ALVC1G07002'(!) = 'ALVC1G07002' |'SOT353_Q'| 'IC(5P) 74LVC1G07GW(SOT353)' | 'PHI'   | '74LVC1G07GW' | ''           | 'EP'      | 'JS1-STEVEN' | 'IC'  | ''      | 'PHI_74LVC1G07.pdf' | ''            | ''     | ''  | ''               | ''      | ''               | '20111207' | 'Normal'

END_PART

END.

